#ISCELL
  cls sheet_a1 *
  *
#ISCELL
  cls offpage_out *
  page127_i101
#ISCELL
  cls gnd_sg *
  page127_i106
#ISCELL
  cls gnd_sg *
  page127_i130
#ISCELL
  cls offpage_out *
  page127_i137
#ISCELL
  cls offpage_in *
  page127_i189
#ISCELL
  cls offpage_in *
  page127_i190
#ISCELL
  cls offpage_in *
  page127_i191
#ISCELL
  cls offpage_in *
  page127_i193
#ISCELL
  cls offpage_in *
  page127_i194
#ISCELL
  cls offpage_in *
  page127_i195
#CELL
  pld xc7a200t_2fbg484c_fbg484 *
  page127_i232
#ISCELL
  cls vcc *
  page127_i243
#ISCELL
  cls offpage_out *
  page127_i260
#ISCELL
  cls offpage_out *
  page127_i261
#ISCELL
  cls offpage_in *
  page127_i267
#ISCELL
  cls offpage_in *
  page127_i268
#ISCELL
  cls offpage_in *
  page127_i293
#ISCELL
  cls offpage_in *
  page127_i294
#ISCELL
  cls offpage_in *
  page127_i295
#ISCELL
  cls offpage_in *
  page127_i296
#ISCELL
  cls offpage_in *
  page127_i297
#ISCELL
  cls offpage_in *
  page127_i298
#ISCELL
  cls offpage_in *
  page127_i299
#ISCELL
  cls offpage_in *
  page127_i300
#ISCELL
  cls offpage_out *
  page127_i302
#ISCELL
  cls offpage_out *
  page127_i303
#ISCELL
  cls offpage_out *
  page127_i305
#ISCELL
  cls offpage_out *
  page127_i306
#ISCELL
  cls offpage_out *
  page127_i307
#ISCELL
  cls offpage_out *
  page127_i308
#CELL
  passive resistor *
  page127_i329
#CELL
  passive resistor *
  page127_i330
#CELL
  passive resistor *
  page127_i331
#CELL
  passive resistor *
  page127_i332
#CELL
  passive resistor *
  page127_i333
#CELL
  passive resistor *
  page127_i334
#CELL
  passive resistor *
  page127_i337
#CELL
  passive resistor *
  page127_i338
#CELL
  passive resistor *
  page127_i339
#ISCELL
  cls offpage_in *
  page127_i361
#ISCELL
  cls offpage_in *
  page127_i362
#ISCELL
  cls vcc *
  page127_i385
#ISCELL
  cls vcc *
  page127_i389
#ISCELL
  cls vcc *
  page127_i390
#CELL
  passive resistor *
  page127_i391
#CELL
  passive resistor *
  page127_i392
#CELL
  passive resistor *
  page127_i393
#CELL
  passive resistor *
  page127_i394
#CELL
  passive resistor *
  page127_i396
#CELL
  passive resistor *
  page127_i397
#ISCELL
  cls gnd_sg *
  page127_i398
#ISCELL
  cls offpage_out *
  page127_i399
#ISCELL
  cls offpage_out *
  page127_i400
#ISCELL
  cls offpage_out *
  page127_i401
#CELL
  passive resistor *
  page127_i402
#CELL
  passive resistor *
  page127_i403
#CELL
  passive resistor *
  page127_i404
#CELL
  passive resistor *
  page127_i405
#CELL
  passive resistor *
  page127_i406
#CELL
  passive resistor *
  page127_i407
#ISCELL
  cls vcc *
  page127_i409
#ISCELL
  cls offpage_in *
  page127_i410
#ISCELL
  cls offpage_in *
  page127_i426
#CELL
  connector g200_10283_01 *
  page127_i427
#ISCELL
  cls offpage_out *
  page127_i428
#ISCELL
  cls offpage_out *
  page127_i429
#ISCELL
  cls offpage_out *
  page127_i430
#ISCELL
  cls offpage_in *
  page127_i431
#CELL
  passive resistor *
  page127_i432
#ISCELL
  cls vcc *
  page127_i433
#CELL
  passive resistor *
  page127_i434
#CELL
  passive resistor *
  page127_i435
#CELL
  passive resistor *
  page127_i436
#CELL
  passive resistor *
  page127_i437
#CELL
  passive resistor *
  page127_i438
#CELL
  passive resistor *
  page127_i439
#CELL
  passive resistor *
  page127_i440
#ISCELL
  cls gnd_sg *
  page127_i441
#CELL
  discrete diode_4_v1 *
  page127_i442
#CELL
  discrete diode_4_v1 *
  page127_i443
#ISCELL
  cls gnd_sg *
  page127_i444
#ISCELL
  cls gnd_sg *
  page127_i445
#CELL
  passive resistor *
  page127_i446
#ISCELL
  cls vcc *
  page127_i447
#ISCELL
  cls offpage_in *
  page127_i452
#ISCELL
  cls offpage_in *
  page127_i453
#ISCELL
  cls offpage_out *
  page127_i454
#ISCELL
  cls offpage_in *
  page127_i455
#CELL
  memory mt25ql128aba1ese_sop8 *
  page127_i456
#ISCELL
  cls vcc *
  page127_i457
#ISCELL
  cls offpage_bi *
  page127_i458
#ISCELL
  cls offpage_bi *
  page127_i459
#ISCELL
  cls offpage_bi *
  page127_i460
#ISCELL
  cls offpage_bi *
  page127_i461
#CELL
  passive resistor *
  page127_i462
#CELL
  passive resistor *
  page127_i463
#CELL
  passive resistor *
  page127_i464
#CELL
  passive resistor *
  page127_i465
#CELL
  passive resistor *
  page127_i466
#CELL
  passive resistor *
  page127_i467
#CELL
  passive resistor *
  page127_i468
#CELL
  passive resistor *
  page127_i469
#CELL
  passive resistor *
  page127_i470
#CELL
  passive resistor *
  page127_i471
#CELL
  passive capacitor *
  page127_i472
#CELL
  passive capacitor *
  page127_i473
#ISCELL
  cls vcc *
  page127_i474
#ISCELL
  cls offpage_in *
  page127_i475
#ISCELL
  cls offpage_in *
  page127_i476
#ISCELL
  cls gnd_sg *
  page127_i477
#ISCELL
  cls gnd_sg *
  page127_i478
#ISCELL
  cls gnd_sg *
  page127_i479
#ISCELL
  cls offpage_in *
  page127_i480
#ISCELL
  cls offpage_in *
  page127_i481
#ISCELL
  cls offpage_out *
  page127_i71
#ISCELL
  cls offpage_out *
  page127_i72
#ISCELL
  cls offpage_out *
  page127_i73
#ISCELL
  cls gnd_sg *
  page127_i75
